(kicad_pcb
	(version 20260206)
	(generator "pcbnew")
	(generator_version "10.0")
	(general
		(thickness 1.6)
		(legacy_teardrops no)
	)
	(paper "A4")
	(title_block
		(title "03242023_DA0F0TMBIJ0_F0T_Motherboard_J_brd_V01_OCP.brd")
		(comment 1 "Grand Teton / footprints 1030-1034 of 6105")
	)
	(layers
		(0 "F.Cu" signal "TOP")
		(4 "In1.Cu" signal "GND")
		(6 "In2.Cu" signal "IN1")
		(8 "In3.Cu" signal "GND1")
		(10 "In4.Cu" signal "IN2")
		(12 "In5.Cu" signal "GND2")
		(14 "In6.Cu" signal "IN3")
		(16 "In7.Cu" signal "GND3")
		(18 "In8.Cu" signal "VCC")
		(20 "In9.Cu" signal "VCC1")
		(22 "In10.Cu" signal "GND4")
		(24 "In11.Cu" signal "IN4")
		(26 "In12.Cu" signal "GND5")
		(28 "In13.Cu" signal "IN5")
		(30 "In14.Cu" signal "GND6")
		(32 "In15.Cu" signal "IN6")
		(34 "In16.Cu" signal "GND7")
		(2 "B.Cu" signal "BOTTOM")
		(9 "F.Adhes" user "F.Adhesive")
		(11 "B.Adhes" user "B.Adhesive")
		(13 "F.Paste" user "Package Geometry/Pastemask Top")
		(15 "B.Paste" user "Package Geometry/Pastemask Bottom")
		(5 "F.SilkS" user "Ref Des/Silkscreen Top")
		(7 "B.SilkS" user "Ref Des/Silkscreen Bottom")
		(1 "F.Mask" user "Board Geometry/Soldermask Top")
		(3 "B.Mask" user "Board Geometry/Soldermask Bottom")
		(17 "Dwgs.User" user "User.Drawings")
		(19 "Cmts.User" user "User.Comments")
		(21 "Eco1.User" user "User.Eco1")
		(23 "Eco2.User" user "User.Eco2")
		(25 "Edge.Cuts" user "Board Geometry/Outline")
		(27 "Margin" user)
		(31 "F.CrtYd" user "Package Geometry/Place Bound Top")
		(29 "B.CrtYd" user "Package Geometry/Place Bound Bottom")
		(35 "F.Fab" user "Ref Des/Assembly Top")
		(33 "B.Fab" user "Ref Des/Assembly Bottom")
	)
	(footprint ""
		(layer "F.Cu")
		(at 221.821502 -70.870318)
		(property "Reference" "PU295"
			(at 4.473448 0.014478 0)
			(unlocked yes)
			(layer "F.SilkS")
			(effects
				(font
					(size 0.7874 0.5842)
					(thickness 0.1524)
				)
				(justify left)
			)
		)
		(property "Value" ""
			(at 0 0 0)
			(layer "F.Fab")
			(effects
				(font
					(size 1.27 1.27)
				)
			)
		)
		(duplicate_pad_numbers_are_jumpers no)
		(fp_line
			(start -1.774952 -1.039876)
			(end -1.774952 1.039876)
			(stroke
				(width 0.1524)
				(type default)
			)
			(layer "F.SilkS")
		)
		(fp_line
			(start -1.774952 1.039876)
			(end 1.774952 1.039876)
			(stroke
				(width 0.1524)
				(type default)
			)
			(layer "F.SilkS")
		)
		(fp_line
			(start 1.774952 -1.039876)
			(end -1.774952 -1.039876)
			(stroke
				(width 0.1524)
				(type default)
			)
			(layer "F.SilkS")
		)
		(fp_line
			(start 1.774952 1.039876)
			(end 1.774952 -1.039876)
			(stroke
				(width 0.1524)
				(type default)
			)
			(layer "F.SilkS")
		)
		(fp_poly
			(pts
				(xy -1.769872 -1.039876) (xy -1.769872 -0.249936) (xy -2.531872 -0.249936) (xy -2.531872 -1.801876)
				(xy -0.999998 -1.801876) (xy -0.999998 -1.039876)
			)
			(stroke
				(width 0)
				(type default)
			)
			(fill yes)
			(layer "F.SilkS")
		)
		(fp_line
			(start -1.769872 -1.039876)
			(end -1.769872 1.039876)
			(stroke
				(width 0.1)
				(type default)
			)
			(layer "F.Fab")
		)
		(fp_line
			(start -1.769872 1.039876)
			(end 1.769872 1.039876)
			(stroke
				(width 0.1)
				(type default)
			)
			(layer "F.Fab")
		)
		(fp_line
			(start 1.769872 -1.039876)
			(end -1.769872 -1.039876)
			(stroke
				(width 0.1)
				(type default)
			)
			(layer "F.Fab")
		)
		(fp_line
			(start 1.769872 1.039876)
			(end 1.769872 -1.039876)
			(stroke
				(width 0.1)
				(type default)
			)
			(layer "F.Fab")
		)
		(fp_poly
			(pts
				(xy -1.769872 -1.039876) (xy -0.999998 -1.039876) (xy -0.999998 -1.801876) (xy -2.531872 -1.801876)
				(xy -2.531872 -0.249936) (xy -1.769872 -0.249936)
			)
			(stroke
				(width 0)
				(type default)
			)
			(fill yes)
			(layer "F.Fab")
		)
		(pad "A1" smd circle
			(at -1.500124 -0.750062)
			(size 0.2286 0.2286)
			(layers "F.Cu" "F.Mask" "F.Paste")
			(net "P3V3_E1S_SENSE_0")
		)
		(pad "A2" smd circle
			(at -0.999998 -0.750062)
			(size 0.2286 0.2286)
			(layers "F.Cu" "F.Mask" "F.Paste")
			(net "P3V3_E1S_VCC_0")
		)
		(pad "A3" smd circle
			(at -0.499872 -0.750062)
			(size 0.2286 0.2286)
			(layers "F.Cu" "F.Mask" "F.Paste")
			(net "P3V3_AUX")
		)
		(pad "A4" smd circle
			(at 0 -0.750062)
			(size 0.2286 0.2286)
			(layers "F.Cu" "F.Mask" "F.Paste")
			(net "P3V3_E1S_0_R")
		)
		(pad "A5" smd circle
			(at 0.499872 -0.750062)
			(size 0.2286 0.2286)
			(layers "F.Cu" "F.Mask" "F.Paste")
			(net "P3V3_AUX")
		)
		(pad "A6" smd circle
			(at 0.999998 -0.750062)
			(size 0.2286 0.2286)
			(layers "F.Cu" "F.Mask" "F.Paste")
			(net "P3V3_E1S_GATE_0")
		)
		(pad "A7" smd circle
			(at 1.500124 -0.750062)
			(size 0.2286 0.2286)
			(layers "F.Cu" "F.Mask" "F.Paste")
			(net "GND")
		)
		(pad "B1" smd circle
			(at -1.500124 -0.249936)
			(size 0.2286 0.2286)
			(layers "F.Cu" "F.Mask" "F.Paste")
			(net "P3V3_E1S_CB_0")
		)
		(pad "B2" smd circle
			(at -0.999998 -0.249936)
			(size 0.2286 0.2286)
			(layers "F.Cu" "F.Mask" "F.Paste")
			(net "GND")
		)
		(pad "B3" smd circle
			(at -0.499872 -0.249936)
			(size 0.2286 0.2286)
			(layers "F.Cu" "F.Mask" "F.Paste")
			(net "P3V3_AUX")
		)
		(pad "B4" smd circle
			(at 0 -0.249936)
			(size 0.2286 0.2286)
			(layers "F.Cu" "F.Mask" "F.Paste")
			(net "P3V3_E1S_0_R")
		)
		(pad "B5" smd circle
			(at 0.499872 -0.249936)
			(size 0.2286 0.2286)
			(layers "F.Cu" "F.Mask" "F.Paste")
			(net "P3V3_AUX")
		)
		(pad "B6" smd circle
			(at 0.999998 -0.249936)
			(size 0.2286 0.2286)
			(layers "F.Cu" "F.Mask" "F.Paste")
			(net "P3V3_E1S_0_R")
		)
		(pad "B7" smd circle
			(at 1.500124 -0.249936)
			(size 0.2286 0.2286)
			(layers "F.Cu" "F.Mask" "F.Paste")
			(net "GND")
		)
		(pad "C1" smd circle
			(at -1.500124 0.249936)
			(size 0.2286 0.2286)
			(layers "F.Cu" "F.Mask" "F.Paste")
			(net "GND")
		)
		(pad "C2" smd circle
			(at -0.999998 0.249936)
			(size 0.2286 0.2286)
			(layers "F.Cu" "F.Mask" "F.Paste")
			(net "GND")
		)
		(pad "C3" smd circle
			(at -0.499872 0.249936)
			(size 0.2286 0.2286)
			(layers "F.Cu" "F.Mask" "F.Paste")
			(net "P3V3_AUX")
		)
		(pad "C4" smd circle
			(at 0 0.249936)
			(size 0.2286 0.2286)
			(layers "F.Cu" "F.Mask" "F.Paste")
			(net "P3V3_E1S_0_R")
		)
		(pad "C5" smd circle
			(at 0.499872 0.249936)
			(size 0.2286 0.2286)
			(layers "F.Cu" "F.Mask" "F.Paste")
			(net "P3V3_AUX")
		)
		(pad "C6" smd circle
			(at 0.999998 0.249936)
			(size 0.2286 0.2286)
			(layers "F.Cu" "F.Mask" "F.Paste")
			(net "P3V3_E1S_0_R")
		)
		(pad "C7" smd circle
			(at 1.500124 0.249936)
			(size 0.2286 0.2286)
			(layers "F.Cu" "F.Mask" "F.Paste")
			(net "P3V3_E1S_FAULT_0")
		)
		(pad "D1" smd circle
			(at -1.500124 0.750062)
			(size 0.2286 0.2286)
			(layers "F.Cu" "F.Mask" "F.Paste")
			(net "P3V3_E1S_REG_0")
		)
		(pad "D2" smd circle
			(at -0.999998 0.750062)
			(size 0.2286 0.2286)
			(layers "F.Cu" "F.Mask" "F.Paste")
			(net "P3V3_E1S_UV_0")
		)
		(pad "D3" smd circle
			(at -0.499872 0.750062)
			(size 0.2286 0.2286)
			(layers "F.Cu" "F.Mask" "F.Paste")
			(net "P3V3_E1S_OV_0")
		)
		(pad "D4" smd circle
			(at 0 0.750062)
			(size 0.2286 0.2286)
			(layers "F.Cu" "F.Mask" "F.Paste")
			(net "P3V3_E1S_0_R")
		)
		(pad "D5" smd circle
			(at 0.499872 0.750062)
			(size 0.2286 0.2286)
			(layers "F.Cu" "F.Mask" "F.Paste")
			(net "P3V3_AUX")
		)
		(pad "D6" smd circle
			(at 0.999998 0.750062)
			(size 0.2286 0.2286)
			(layers "F.Cu" "F.Mask" "F.Paste")
			(net "P3V3_E1S_0_R")
		)
		(pad "D7" smd circle
			(at 1.500124 0.750062)
			(size 0.2286 0.2286)
			(layers "F.Cu" "F.Mask" "F.Paste")
			(net "P3V3_E1S_PWRGD_0")
		)
	)
	(footprint ""
		(layer "F.Cu")
		(at 81.82737 -59.364626 -90)
		(property "Reference" "PC2147"
			(at 0 0 270)
			(layer "F.SilkS")
			(hide yes)
			(effects
				(font
					(size 1.27 1.27)
				)
			)
		)
		(property "Value" ""
			(at 0 0 270)
			(layer "F.Fab")
			(effects
				(font
					(size 1.27 1.27)
				)
			)
		)
		(duplicate_pad_numbers_are_jumpers no)
		(fp_line
			(start -0.7874 0.4064)
			(end -0.7874 -0.4064)
			(stroke
				(width 0.1524)
				(type default)
			)
			(layer "F.SilkS")
		)
		(fp_line
			(start 0.7874 0.4064)
			(end -0.7874 0.4064)
			(stroke
				(width 0.1524)
				(type default)
			)
			(layer "F.SilkS")
		)
		(fp_line
			(start -0.7874 -0.4064)
			(end 0.7874 -0.4064)
			(stroke
				(width 0.1524)
				(type default)
			)
			(layer "F.SilkS")
		)
		(fp_line
			(start 0.7874 -0.4064)
			(end 0.7874 0.4064)
			(stroke
				(width 0.1524)
				(type default)
			)
			(layer "F.SilkS")
		)
		(fp_line
			(start -0.67945 0.3048)
			(end -0.67945 -0.305054)
			(stroke
				(width 0.1)
				(type default)
			)
			(layer "F.Fab")
		)
		(fp_line
			(start -0.12065 0.3048)
			(end -0.67945 0.3048)
			(stroke
				(width 0.1)
				(type default)
			)
			(layer "F.Fab")
		)
		(fp_line
			(start 0.120396 0.3048)
			(end 0.120396 0.2794)
			(stroke
				(width 0.1)
				(type default)
			)
			(layer "F.Fab")
		)
		(fp_line
			(start 0.67945 0.3048)
			(end 0.120396 0.3048)
			(stroke
				(width 0.1)
				(type default)
			)
			(layer "F.Fab")
		)
		(fp_line
			(start -0.12065 0.2794)
			(end -0.12065 0.3048)
			(stroke
				(width 0.1)
				(type default)
			)
			(layer "F.Fab")
		)
		(fp_line
			(start 0.120396 0.2794)
			(end -0.12065 0.2794)
			(stroke
				(width 0.1)
				(type default)
			)
			(layer "F.Fab")
		)
		(fp_line
			(start -0.12065 -0.2794)
			(end 0.12065 -0.2794)
			(stroke
				(width 0.1)
				(type default)
			)
			(layer "F.Fab")
		)
		(fp_line
			(start 0.12065 -0.2794)
			(end 0.12065 -0.3048)
			(stroke
				(width 0.1)
				(type default)
			)
			(layer "F.Fab")
		)
		(fp_line
			(start 0.12065 -0.3048)
			(end 0.67945 -0.3048)
			(stroke
				(width 0.1)
				(type default)
			)
			(layer "F.Fab")
		)
		(fp_line
			(start 0.67945 -0.3048)
			(end 0.67945 0.3048)
			(stroke
				(width 0.1)
				(type default)
			)
			(layer "F.Fab")
		)
		(fp_line
			(start -0.67945 -0.305054)
			(end -0.12065 -0.305054)
			(stroke
				(width 0.1)
				(type default)
			)
			(layer "F.Fab")
		)
		(fp_line
			(start -0.12065 -0.305054)
			(end -0.12065 -0.2794)
			(stroke
				(width 0.1)
				(type default)
			)
			(layer "F.Fab")
		)
		(pad "1" smd circle
			(at -0.40005 0 270)
			(size 0 0)
			(layers "F.Cu" "F.Mask" "F.Paste")
			(net "GND")
		)
		(pad "2" smd circle
			(at 0.40005 0 270)
			(size 0 0)
			(layers "F.Cu" "F.Mask" "F.Paste")
			(net "P3V3_OCP_REG_2")
		)
	)
	(footprint ""
		(layer "F.Cu")
		(at 292.236398 -18.714466 180)
		(property "Reference" "C2276"
			(at 0 0 180)
			(layer "F.SilkS")
			(hide yes)
			(effects
				(font
					(size 1.27 1.27)
				)
			)
		)
		(property "Value" ""
			(at 0 0 180)
			(layer "F.Fab")
			(effects
				(font
					(size 1.27 1.27)
				)
			)
		)
		(duplicate_pad_numbers_are_jumpers no)
		(fp_line
			(start 0.7874 0.4064)
			(end -0.7874 0.4064)
			(stroke
				(width 0.1524)
				(type default)
			)
			(layer "F.SilkS")
		)
		(fp_line
			(start 0.7874 -0.4064)
			(end 0.7874 0.4064)
			(stroke
				(width 0.1524)
				(type default)
			)
			(layer "F.SilkS")
		)
		(fp_line
			(start -0.7874 0.4064)
			(end -0.7874 -0.4064)
			(stroke
				(width 0.1524)
				(type default)
			)
			(layer "F.SilkS")
		)
		(fp_line
			(start -0.7874 -0.4064)
			(end 0.7874 -0.4064)
			(stroke
				(width 0.1524)
				(type default)
			)
			(layer "F.SilkS")
		)
		(fp_line
			(start 0.67945 0.3048)
			(end 0.120396 0.3048)
			(stroke
				(width 0.1)
				(type default)
			)
			(layer "F.Fab")
		)
		(fp_line
			(start 0.67945 -0.3048)
			(end 0.67945 0.3048)
			(stroke
				(width 0.1)
				(type default)
			)
			(layer "F.Fab")
		)
		(fp_line
			(start 0.12065 -0.2794)
			(end 0.12065 -0.3048)
			(stroke
				(width 0.1)
				(type default)
			)
			(layer "F.Fab")
		)
		(fp_line
			(start 0.12065 -0.3048)
			(end 0.67945 -0.3048)
			(stroke
				(width 0.1)
				(type default)
			)
			(layer "F.Fab")
		)
		(fp_line
			(start 0.120396 0.3048)
			(end 0.120396 0.2794)
			(stroke
				(width 0.1)
				(type default)
			)
			(layer "F.Fab")
		)
		(fp_line
			(start 0.120396 0.2794)
			(end -0.12065 0.2794)
			(stroke
				(width 0.1)
				(type default)
			)
			(layer "F.Fab")
		)
		(fp_line
			(start -0.12065 0.3048)
			(end -0.67945 0.3048)
			(stroke
				(width 0.1)
				(type default)
			)
			(layer "F.Fab")
		)
		(fp_line
			(start -0.12065 0.2794)
			(end -0.12065 0.3048)
			(stroke
				(width 0.1)
				(type default)
			)
			(layer "F.Fab")
		)
		(fp_line
			(start -0.12065 -0.2794)
			(end 0.12065 -0.2794)
			(stroke
				(width 0.1)
				(type default)
			)
			(layer "F.Fab")
		)
		(fp_line
			(start -0.12065 -0.305054)
			(end -0.12065 -0.2794)
			(stroke
				(width 0.1)
				(type default)
			)
			(layer "F.Fab")
		)
		(fp_line
			(start -0.67945 0.3048)
			(end -0.67945 -0.305054)
			(stroke
				(width 0.1)
				(type default)
			)
			(layer "F.Fab")
		)
		(fp_line
			(start -0.67945 -0.305054)
			(end -0.12065 -0.305054)
			(stroke
				(width 0.1)
				(type default)
			)
			(layer "F.Fab")
		)
		(pad "1" smd circle
			(at -0.40005 0 180)
			(size 0 0)
			(layers "F.Cu" "F.Mask" "F.Paste")
			(net "P3V3_AUX")
		)
		(pad "2" smd circle
			(at 0.40005 0 180)
			(size 0 0)
			(layers "F.Cu" "F.Mask" "F.Paste")
			(net "GND")
		)
	)
	(footprint ""
		(layer "F.Cu")
		(at 54.242716 -108.89869 180)
		(property "Reference" "R3717"
			(at 0 0 180)
			(layer "F.SilkS")
			(hide yes)
			(effects
				(font
					(size 1.27 1.27)
				)
			)
		)
		(property "Value" ""
			(at 0 0 180)
			(layer "F.Fab")
			(effects
				(font
					(size 1.27 1.27)
				)
			)
		)
		(duplicate_pad_numbers_are_jumpers no)
		(fp_line
			(start 0.7874 0.4064)
			(end -0.7874 0.4064)
			(stroke
				(width 0.1524)
				(type default)
			)
			(layer "F.SilkS")
		)
		(fp_line
			(start 0.7874 -0.4064)
			(end 0.7874 0.4064)
			(stroke
				(width 0.1524)
				(type default)
			)
			(layer "F.SilkS")
		)
		(fp_line
			(start -0.7874 0.4064)
			(end -0.7874 -0.4064)
			(stroke
				(width 0.1524)
				(type default)
			)
			(layer "F.SilkS")
		)
		(fp_line
			(start -0.7874 -0.4064)
			(end 0.7874 -0.4064)
			(stroke
				(width 0.1524)
				(type default)
			)
			(layer "F.SilkS")
		)
		(fp_line
			(start 0.67945 0.3048)
			(end 0.120396 0.3048)
			(stroke
				(width 0.1)
				(type default)
			)
			(layer "F.Fab")
		)
		(fp_line
			(start 0.67945 -0.3048)
			(end 0.67945 0.3048)
			(stroke
				(width 0.1)
				(type default)
			)
			(layer "F.Fab")
		)
		(fp_line
			(start 0.12065 -0.2794)
			(end 0.12065 -0.3048)
			(stroke
				(width 0.1)
				(type default)
			)
			(layer "F.Fab")
		)
		(fp_line
			(start 0.12065 -0.3048)
			(end 0.67945 -0.3048)
			(stroke
				(width 0.1)
				(type default)
			)
			(layer "F.Fab")
		)
		(fp_line
			(start 0.120396 0.3048)
			(end 0.120396 0.2794)
			(stroke
				(width 0.1)
				(type default)
			)
			(layer "F.Fab")
		)
		(fp_line
			(start 0.120396 0.2794)
			(end -0.12065 0.2794)
			(stroke
				(width 0.1)
				(type default)
			)
			(layer "F.Fab")
		)
		(fp_line
			(start -0.12065 0.3048)
			(end -0.67945 0.3048)
			(stroke
				(width 0.1)
				(type default)
			)
			(layer "F.Fab")
		)
		(fp_line
			(start -0.12065 0.2794)
			(end -0.12065 0.3048)
			(stroke
				(width 0.1)
				(type default)
			)
			(layer "F.Fab")
		)
		(fp_line
			(start -0.12065 -0.2794)
			(end 0.12065 -0.2794)
			(stroke
				(width 0.1)
				(type default)
			)
			(layer "F.Fab")
		)
		(fp_line
			(start -0.12065 -0.305054)
			(end -0.12065 -0.2794)
			(stroke
				(width 0.1)
				(type default)
			)
			(layer "F.Fab")
		)
		(fp_line
			(start -0.67945 0.3048)
			(end -0.67945 -0.305054)
			(stroke
				(width 0.1)
				(type default)
			)
			(layer "F.Fab")
		)
		(fp_line
			(start -0.67945 -0.305054)
			(end -0.12065 -0.305054)
			(stroke
				(width 0.1)
				(type default)
			)
			(layer "F.Fab")
		)
		(pad "1" smd circle
			(at -0.40005 0 180)
			(size 0 0)
			(layers "F.Cu" "F.Mask" "F.Paste")
			(net "SMB_LM75_1_3V3AUX_SCL_R")
		)
		(pad "2" smd circle
			(at 0.40005 0 180)
			(size 0 0)
			(layers "F.Cu" "F.Mask" "F.Paste")
			(net "SMB_LM75_1_3V3AUX_SCL")
		)
	)
	(footprint ""
		(layer "F.Cu")
		(at 294.82288 -46.954948 -90)
		(property "Reference" "R4073"
			(at 0 0 270)
			(layer "F.SilkS")
			(hide yes)
			(effects
				(font
					(size 1.27 1.27)
				)
			)
		)
		(property "Value" ""
			(at 0 0 270)
			(layer "F.Fab")
			(effects
				(font
					(size 1.27 1.27)
				)
			)
		)
		(duplicate_pad_numbers_are_jumpers no)
		(fp_line
			(start -0.7874 0.4064)
			(end -0.7874 -0.4064)
			(stroke
				(width 0.1524)
				(type default)
			)
			(layer "F.SilkS")
		)
		(fp_line
			(start 0.7874 0.4064)
			(end -0.7874 0.4064)
			(stroke
				(width 0.1524)
				(type default)
			)
			(layer "F.SilkS")
		)
		(fp_line
			(start -0.7874 -0.4064)
			(end 0.7874 -0.4064)
			(stroke
				(width 0.1524)
				(type default)
			)
			(layer "F.SilkS")
		)
		(fp_line
			(start 0.7874 -0.4064)
			(end 0.7874 0.4064)
			(stroke
				(width 0.1524)
				(type default)
			)
			(layer "F.SilkS")
		)
		(fp_line
			(start -0.67945 0.3048)
			(end -0.67945 -0.305054)
			(stroke
				(width 0.1)
				(type default)
			)
			(layer "F.Fab")
		)
		(fp_line
			(start -0.12065 0.3048)
			(end -0.67945 0.3048)
			(stroke
				(width 0.1)
				(type default)
			)
			(layer "F.Fab")
		)
		(fp_line
			(start 0.120396 0.3048)
			(end 0.120396 0.2794)
			(stroke
				(width 0.1)
				(type default)
			)
			(layer "F.Fab")
		)
		(fp_line
			(start 0.67945 0.3048)
			(end 0.120396 0.3048)
			(stroke
				(width 0.1)
				(type default)
			)
			(layer "F.Fab")
		)
		(fp_line
			(start -0.12065 0.2794)
			(end -0.12065 0.3048)
			(stroke
				(width 0.1)
				(type default)
			)
			(layer "F.Fab")
		)
		(fp_line
			(start 0.120396 0.2794)
			(end -0.12065 0.2794)
			(stroke
				(width 0.1)
				(type default)
			)
			(layer "F.Fab")
		)
		(fp_line
			(start -0.12065 -0.2794)
			(end 0.12065 -0.2794)
			(stroke
				(width 0.1)
				(type default)
			)
			(layer "F.Fab")
		)
		(fp_line
			(start 0.12065 -0.2794)
			(end 0.12065 -0.3048)
			(stroke
				(width 0.1)
				(type default)
			)
			(layer "F.Fab")
		)
		(fp_line
			(start 0.12065 -0.3048)
			(end 0.67945 -0.3048)
			(stroke
				(width 0.1)
				(type default)
			)
			(layer "F.Fab")
		)
		(fp_line
			(start 0.67945 -0.3048)
			(end 0.67945 0.3048)
			(stroke
				(width 0.1)
				(type default)
			)
			(layer "F.Fab")
		)
		(fp_line
			(start -0.67945 -0.305054)
			(end -0.12065 -0.305054)
			(stroke
				(width 0.1)
				(type default)
			)
			(layer "F.Fab")
		)
		(fp_line
			(start -0.12065 -0.305054)
			(end -0.12065 -0.2794)
			(stroke
				(width 0.1)
				(type default)
			)
			(layer "F.Fab")
		)
		(pad "1" smd circle
			(at -0.40005 0 270)
			(size 0 0)
			(layers "F.Cu" "F.Mask" "F.Paste")
			(net "P12V_E1S_EN_0_R")
		)
		(pad "2" smd circle
			(at 0.40005 0 270)
			(size 0 0)
			(layers "F.Cu" "F.Mask" "F.Paste")
			(net "GND")
		)
	)
)
